(kicad_pcb
	(version 20260206)
	(generator "pcbnew")
	(generator_version "10.0")
	(general
		(thickness 1.6)
		(legacy_teardrops no)
	)
	(paper "A4")
	(title_block
		(title "04192023_DAF0TMB3IC0_F0TG_MB_C_brd_V02_OCP.brd")
		(comment 1 "Grand Teton / footprints 6133-6139 of 8354")
	)
	(layers
		(0 "F.Cu" signal "TOP")
		(4 "In1.Cu" signal "GND")
		(6 "In2.Cu" signal "IN1")
		(8 "In3.Cu" signal "GND1")
		(10 "In4.Cu" signal "IN2")
		(12 "In5.Cu" signal "GND2")
		(14 "In6.Cu" signal "IN3")
		(16 "In7.Cu" signal "GND3")
		(18 "In8.Cu" signal "VCC")
		(20 "In9.Cu" signal "VCC1")
		(22 "In10.Cu" signal "GND4")
		(24 "In11.Cu" signal "IN4")
		(26 "In12.Cu" signal "GND5")
		(28 "In13.Cu" signal "IN5")
		(30 "In14.Cu" signal "GND6")
		(32 "In15.Cu" signal "IN6")
		(34 "In16.Cu" signal "GND7")
		(2 "B.Cu" signal "BOTTOM")
		(9 "F.Adhes" user "F.Adhesive")
		(11 "B.Adhes" user "B.Adhesive")
		(13 "F.Paste" user "Package Geometry/Pastemask Top")
		(15 "B.Paste" user "Package Geometry/Pastemask Bottom")
		(5 "F.SilkS" user "Ref Des/Silkscreen Top")
		(7 "B.SilkS" user "Ref Des/Silkscreen Bottom")
		(1 "F.Mask" user "Board Geometry/Soldermask Top")
		(3 "B.Mask" user "Board Geometry/Soldermask Bottom")
		(17 "Dwgs.User" user "User.Drawings")
		(19 "Cmts.User" user "User.Comments")
		(21 "Eco1.User" user "User.Eco1")
		(23 "Eco2.User" user "User.Eco2")
		(25 "Edge.Cuts" user "Board Geometry/Outline")
		(27 "Margin" user)
		(31 "F.CrtYd" user "Package Geometry/Place Bound Top")
		(29 "B.CrtYd" user "Package Geometry/Place Bound Bottom")
		(35 "F.Fab" user "Ref Des/Assembly Top")
		(33 "B.Fab" user "Ref Des/Assembly Bottom")
	)
	(footprint ""
		(layer "B.Cu")
		(at 372.937278 -145.536158 180)
		(property "Reference" "PR8005"
			(at 0 0 0)
			(layer "B.SilkS")
			(hide yes)
			(effects
				(font
					(size 1.27 1.27)
				)
				(justify mirror)
			)
		)
		(property "Value" ""
			(at 0 0 0)
			(layer "B.Fab")
			(effects
				(font
					(size 1.27 1.27)
				)
				(justify mirror)
			)
		)
		(duplicate_pad_numbers_are_jumpers no)
		(fp_line
			(start 0.7874 0.4064)
			(end 0.7874 -0.4064)
			(stroke
				(width 0.1524)
				(type default)
			)
			(layer "B.SilkS")
		)
		(fp_line
			(start 0.7874 -0.4064)
			(end -0.7874 -0.4064)
			(stroke
				(width 0.1524)
				(type default)
			)
			(layer "B.SilkS")
		)
		(fp_line
			(start -0.7874 0.4064)
			(end 0.7874 0.4064)
			(stroke
				(width 0.1524)
				(type default)
			)
			(layer "B.SilkS")
		)
		(fp_line
			(start -0.7874 -0.4064)
			(end -0.7874 0.4064)
			(stroke
				(width 0.1524)
				(type default)
			)
			(layer "B.SilkS")
		)
		(fp_line
			(start 0.67945 0.3048)
			(end 0.67945 -0.305054)
			(stroke
				(width 0.1)
				(type default)
			)
			(layer "B.Fab")
		)
		(fp_line
			(start 0.67945 -0.305054)
			(end 0.12065 -0.305054)
			(stroke
				(width 0.1)
				(type default)
			)
			(layer "B.Fab")
		)
		(fp_line
			(start 0.12065 0.3048)
			(end 0.67945 0.3048)
			(stroke
				(width 0.1)
				(type default)
			)
			(layer "B.Fab")
		)
		(fp_line
			(start 0.12065 0.2794)
			(end 0.12065 0.3048)
			(stroke
				(width 0.1)
				(type default)
			)
			(layer "B.Fab")
		)
		(fp_line
			(start 0.12065 -0.2794)
			(end -0.12065 -0.2794)
			(stroke
				(width 0.1)
				(type default)
			)
			(layer "B.Fab")
		)
		(fp_line
			(start 0.12065 -0.305054)
			(end 0.12065 -0.2794)
			(stroke
				(width 0.1)
				(type default)
			)
			(layer "B.Fab")
		)
		(fp_line
			(start -0.120396 0.3048)
			(end -0.120396 0.2794)
			(stroke
				(width 0.1)
				(type default)
			)
			(layer "B.Fab")
		)
		(fp_line
			(start -0.120396 0.2794)
			(end 0.12065 0.2794)
			(stroke
				(width 0.1)
				(type default)
			)
			(layer "B.Fab")
		)
		(fp_line
			(start -0.12065 -0.2794)
			(end -0.12065 -0.3048)
			(stroke
				(width 0.1)
				(type default)
			)
			(layer "B.Fab")
		)
		(fp_line
			(start -0.12065 -0.3048)
			(end -0.67945 -0.3048)
			(stroke
				(width 0.1)
				(type default)
			)
			(layer "B.Fab")
		)
		(fp_line
			(start -0.67945 0.3048)
			(end -0.120396 0.3048)
			(stroke
				(width 0.1)
				(type default)
			)
			(layer "B.Fab")
		)
		(fp_line
			(start -0.67945 -0.3048)
			(end -0.67945 0.3048)
			(stroke
				(width 0.1)
				(type default)
			)
			(layer "B.Fab")
		)
		(pad "1" smd circle
			(at 0.40005 0)
			(size 0 0)
			(layers "B.Cu" "B.Mask" "B.Paste")
			(net "SVID_PVDDCR_CPU0_P0_SVC_R")
		)
		(pad "2" smd circle
			(at -0.40005 0)
			(size 0 0)
			(layers "B.Cu" "B.Mask" "B.Paste")
			(net "SVID_PVDDCR_CPU0_P0_SVC_R1")
		)
	)
	(footprint ""
		(layer "B.Cu")
		(at 420.667688 -193.99631)
		(property "Reference" "R97"
			(at 0 0 0)
			(layer "B.SilkS")
			(hide yes)
			(effects
				(font
					(size 1.27 1.27)
				)
				(justify mirror)
			)
		)
		(property "Value" ""
			(at 0 0 0)
			(layer "B.Fab")
			(effects
				(font
					(size 1.27 1.27)
				)
				(justify mirror)
			)
		)
		(duplicate_pad_numbers_are_jumpers no)
		(fp_line
			(start -0.7874 -0.4064)
			(end -0.7874 0.4064)
			(stroke
				(width 0.1524)
				(type default)
			)
			(layer "B.SilkS")
		)
		(fp_line
			(start -0.7874 0.4064)
			(end 0.7874 0.4064)
			(stroke
				(width 0.1524)
				(type default)
			)
			(layer "B.SilkS")
		)
		(fp_line
			(start 0.7874 -0.4064)
			(end -0.7874 -0.4064)
			(stroke
				(width 0.1524)
				(type default)
			)
			(layer "B.SilkS")
		)
		(fp_line
			(start 0.7874 0.4064)
			(end 0.7874 -0.4064)
			(stroke
				(width 0.1524)
				(type default)
			)
			(layer "B.SilkS")
		)
		(fp_line
			(start -0.67945 -0.3048)
			(end -0.67945 0.3048)
			(stroke
				(width 0.1)
				(type default)
			)
			(layer "B.Fab")
		)
		(fp_line
			(start -0.67945 0.3048)
			(end -0.120396 0.3048)
			(stroke
				(width 0.1)
				(type default)
			)
			(layer "B.Fab")
		)
		(fp_line
			(start -0.12065 -0.3048)
			(end -0.67945 -0.3048)
			(stroke
				(width 0.1)
				(type default)
			)
			(layer "B.Fab")
		)
		(fp_line
			(start -0.12065 -0.2794)
			(end -0.12065 -0.3048)
			(stroke
				(width 0.1)
				(type default)
			)
			(layer "B.Fab")
		)
		(fp_line
			(start -0.120396 0.2794)
			(end 0.12065 0.2794)
			(stroke
				(width 0.1)
				(type default)
			)
			(layer "B.Fab")
		)
		(fp_line
			(start -0.120396 0.3048)
			(end -0.120396 0.2794)
			(stroke
				(width 0.1)
				(type default)
			)
			(layer "B.Fab")
		)
		(fp_line
			(start 0.12065 -0.305054)
			(end 0.12065 -0.2794)
			(stroke
				(width 0.1)
				(type default)
			)
			(layer "B.Fab")
		)
		(fp_line
			(start 0.12065 -0.2794)
			(end -0.12065 -0.2794)
			(stroke
				(width 0.1)
				(type default)
			)
			(layer "B.Fab")
		)
		(fp_line
			(start 0.12065 0.2794)
			(end 0.12065 0.3048)
			(stroke
				(width 0.1)
				(type default)
			)
			(layer "B.Fab")
		)
		(fp_line
			(start 0.12065 0.3048)
			(end 0.67945 0.3048)
			(stroke
				(width 0.1)
				(type default)
			)
			(layer "B.Fab")
		)
		(fp_line
			(start 0.67945 -0.305054)
			(end 0.12065 -0.305054)
			(stroke
				(width 0.1)
				(type default)
			)
			(layer "B.Fab")
		)
		(fp_line
			(start 0.67945 0.3048)
			(end 0.67945 -0.305054)
			(stroke
				(width 0.1)
				(type default)
			)
			(layer "B.Fab")
		)
		(pad "1" smd circle
			(at 0.40005 0 180)
			(size 0 0)
			(layers "B.Cu" "B.Mask" "B.Paste")
			(net "P3V3")
		)
		(pad "2" smd circle
			(at -0.40005 0 180)
			(size 0 0)
			(layers "B.Cu" "B.Mask" "B.Paste")
			(net "PWRGD_CHH_CPU0_DIMM")
		)
	)
	(footprint ""
		(layer "B.Cu")
		(at 389.845296 -398.942052 90)
		(property "Reference" "C1040"
			(at 0 0 90)
			(layer "B.SilkS")
			(hide yes)
			(effects
				(font
					(size 1.27 1.27)
				)
				(justify mirror)
			)
		)
		(property "Value" ""
			(at 0 0 90)
			(layer "B.Fab")
			(effects
				(font
					(size 1.27 1.27)
				)
				(justify mirror)
			)
		)
		(duplicate_pad_numbers_are_jumpers no)
		(fp_line
			(start 0.7874 -0.4064)
			(end -0.7874 -0.4064)
			(stroke
				(width 0.1524)
				(type default)
			)
			(layer "B.SilkS")
		)
		(fp_line
			(start -0.7874 -0.4064)
			(end -0.7874 0.4064)
			(stroke
				(width 0.1524)
				(type default)
			)
			(layer "B.SilkS")
		)
		(fp_line
			(start 0.7874 0.4064)
			(end 0.7874 -0.4064)
			(stroke
				(width 0.1524)
				(type default)
			)
			(layer "B.SilkS")
		)
		(fp_line
			(start -0.7874 0.4064)
			(end 0.7874 0.4064)
			(stroke
				(width 0.1524)
				(type default)
			)
			(layer "B.SilkS")
		)
		(fp_line
			(start 0.67945 -0.305054)
			(end 0.12065 -0.305054)
			(stroke
				(width 0.1)
				(type default)
			)
			(layer "B.Fab")
		)
		(fp_line
			(start 0.12065 -0.305054)
			(end 0.12065 -0.2794)
			(stroke
				(width 0.1)
				(type default)
			)
			(layer "B.Fab")
		)
		(fp_line
			(start -0.12065 -0.3048)
			(end -0.67945 -0.3048)
			(stroke
				(width 0.1)
				(type default)
			)
			(layer "B.Fab")
		)
		(fp_line
			(start -0.67945 -0.3048)
			(end -0.67945 0.3048)
			(stroke
				(width 0.1)
				(type default)
			)
			(layer "B.Fab")
		)
		(fp_line
			(start 0.12065 -0.2794)
			(end -0.12065 -0.2794)
			(stroke
				(width 0.1)
				(type default)
			)
			(layer "B.Fab")
		)
		(fp_line
			(start -0.12065 -0.2794)
			(end -0.12065 -0.3048)
			(stroke
				(width 0.1)
				(type default)
			)
			(layer "B.Fab")
		)
		(fp_line
			(start 0.12065 0.2794)
			(end 0.12065 0.3048)
			(stroke
				(width 0.1)
				(type default)
			)
			(layer "B.Fab")
		)
		(fp_line
			(start -0.120396 0.2794)
			(end 0.12065 0.2794)
			(stroke
				(width 0.1)
				(type default)
			)
			(layer "B.Fab")
		)
		(fp_line
			(start 0.67945 0.3048)
			(end 0.67945 -0.305054)
			(stroke
				(width 0.1)
				(type default)
			)
			(layer "B.Fab")
		)
		(fp_line
			(start 0.12065 0.3048)
			(end 0.67945 0.3048)
			(stroke
				(width 0.1)
				(type default)
			)
			(layer "B.Fab")
		)
		(fp_line
			(start -0.120396 0.3048)
			(end -0.120396 0.2794)
			(stroke
				(width 0.1)
				(type default)
			)
			(layer "B.Fab")
		)
		(fp_line
			(start -0.67945 0.3048)
			(end -0.120396 0.3048)
			(stroke
				(width 0.1)
				(type default)
			)
			(layer "B.Fab")
		)
		(pad "1" smd circle
			(at 0.40005 0 270)
			(size 0 0)
			(layers "B.Cu" "B.Mask" "B.Paste")
			(net "P0V9_CPU0_RT3_2A")
		)
		(pad "2" smd circle
			(at -0.40005 0 270)
			(size 0 0)
			(layers "B.Cu" "B.Mask" "B.Paste")
			(net "GND")
		)
	)
	(footprint ""
		(layer "B.Cu")
		(at 157.026864 -350.289622 180)
		(property "Reference" "R8386"
			(at 0 0 0)
			(layer "B.SilkS")
			(hide yes)
			(effects
				(font
					(size 1.27 1.27)
				)
				(justify mirror)
			)
		)
		(property "Value" ""
			(at 0 0 0)
			(layer "B.Fab")
			(effects
				(font
					(size 1.27 1.27)
				)
				(justify mirror)
			)
		)
		(duplicate_pad_numbers_are_jumpers no)
		(fp_line
			(start 0.7874 0.4064)
			(end 0.7874 -0.4064)
			(stroke
				(width 0.1524)
				(type default)
			)
			(layer "B.SilkS")
		)
		(fp_line
			(start 0.7874 -0.4064)
			(end -0.7874 -0.4064)
			(stroke
				(width 0.1524)
				(type default)
			)
			(layer "B.SilkS")
		)
		(fp_line
			(start -0.7874 0.4064)
			(end 0.7874 0.4064)
			(stroke
				(width 0.1524)
				(type default)
			)
			(layer "B.SilkS")
		)
		(fp_line
			(start -0.7874 -0.4064)
			(end -0.7874 0.4064)
			(stroke
				(width 0.1524)
				(type default)
			)
			(layer "B.SilkS")
		)
		(fp_line
			(start 0.67945 0.3048)
			(end 0.67945 -0.305054)
			(stroke
				(width 0.1)
				(type default)
			)
			(layer "B.Fab")
		)
		(fp_line
			(start 0.67945 -0.305054)
			(end 0.12065 -0.305054)
			(stroke
				(width 0.1)
				(type default)
			)
			(layer "B.Fab")
		)
		(fp_line
			(start 0.12065 0.3048)
			(end 0.67945 0.3048)
			(stroke
				(width 0.1)
				(type default)
			)
			(layer "B.Fab")
		)
		(fp_line
			(start 0.12065 0.2794)
			(end 0.12065 0.3048)
			(stroke
				(width 0.1)
				(type default)
			)
			(layer "B.Fab")
		)
		(fp_line
			(start 0.12065 -0.2794)
			(end -0.12065 -0.2794)
			(stroke
				(width 0.1)
				(type default)
			)
			(layer "B.Fab")
		)
		(fp_line
			(start 0.12065 -0.305054)
			(end 0.12065 -0.2794)
			(stroke
				(width 0.1)
				(type default)
			)
			(layer "B.Fab")
		)
		(fp_line
			(start -0.120396 0.3048)
			(end -0.120396 0.2794)
			(stroke
				(width 0.1)
				(type default)
			)
			(layer "B.Fab")
		)
		(fp_line
			(start -0.120396 0.2794)
			(end 0.12065 0.2794)
			(stroke
				(width 0.1)
				(type default)
			)
			(layer "B.Fab")
		)
		(fp_line
			(start -0.12065 -0.2794)
			(end -0.12065 -0.3048)
			(stroke
				(width 0.1)
				(type default)
			)
			(layer "B.Fab")
		)
		(fp_line
			(start -0.12065 -0.3048)
			(end -0.67945 -0.3048)
			(stroke
				(width 0.1)
				(type default)
			)
			(layer "B.Fab")
		)
		(fp_line
			(start -0.67945 0.3048)
			(end -0.120396 0.3048)
			(stroke
				(width 0.1)
				(type default)
			)
			(layer "B.Fab")
		)
		(fp_line
			(start -0.67945 -0.3048)
			(end -0.67945 0.3048)
			(stroke
				(width 0.1)
				(type default)
			)
			(layer "B.Fab")
		)
		(pad "1" smd circle
			(at 0.40005 0)
			(size 0 0)
			(layers "B.Cu" "B.Mask" "B.Paste")
			(net "PVDD11_S3_P1_EN")
		)
		(pad "2" smd circle
			(at -0.40005 0)
			(size 0 0)
			(layers "B.Cu" "B.Mask" "B.Paste")
			(net "PVDD11_S3_P1_EN_R")
		)
	)
	(footprint ""
		(layer "B.Cu")
		(at 117.896386 -250.892564)
		(property "Reference" "C2414"
			(at 0 0 0)
			(layer "B.SilkS")
			(hide yes)
			(effects
				(font
					(size 1.27 1.27)
				)
				(justify mirror)
			)
		)
		(property "Value" ""
			(at 0 0 0)
			(layer "B.Fab")
			(effects
				(font
					(size 1.27 1.27)
				)
				(justify mirror)
			)
		)
		(duplicate_pad_numbers_are_jumpers no)
		(fp_line
			(start -0.7874 -0.4064)
			(end -0.7874 0.4064)
			(stroke
				(width 0.1524)
				(type default)
			)
			(layer "B.SilkS")
		)
		(fp_line
			(start -0.7874 0.4064)
			(end 0.7874 0.4064)
			(stroke
				(width 0.1524)
				(type default)
			)
			(layer "B.SilkS")
		)
		(fp_line
			(start 0.7874 -0.4064)
			(end -0.7874 -0.4064)
			(stroke
				(width 0.1524)
				(type default)
			)
			(layer "B.SilkS")
		)
		(fp_line
			(start 0.7874 0.4064)
			(end 0.7874 -0.4064)
			(stroke
				(width 0.1524)
				(type default)
			)
			(layer "B.SilkS")
		)
		(fp_line
			(start -0.67945 -0.3048)
			(end -0.67945 0.3048)
			(stroke
				(width 0.1)
				(type default)
			)
			(layer "B.Fab")
		)
		(fp_line
			(start -0.67945 0.3048)
			(end -0.120396 0.3048)
			(stroke
				(width 0.1)
				(type default)
			)
			(layer "B.Fab")
		)
		(fp_line
			(start -0.12065 -0.3048)
			(end -0.67945 -0.3048)
			(stroke
				(width 0.1)
				(type default)
			)
			(layer "B.Fab")
		)
		(fp_line
			(start -0.12065 -0.2794)
			(end -0.12065 -0.3048)
			(stroke
				(width 0.1)
				(type default)
			)
			(layer "B.Fab")
		)
		(fp_line
			(start -0.120396 0.2794)
			(end 0.12065 0.2794)
			(stroke
				(width 0.1)
				(type default)
			)
			(layer "B.Fab")
		)
		(fp_line
			(start -0.120396 0.3048)
			(end -0.120396 0.2794)
			(stroke
				(width 0.1)
				(type default)
			)
			(layer "B.Fab")
		)
		(fp_line
			(start 0.12065 -0.305054)
			(end 0.12065 -0.2794)
			(stroke
				(width 0.1)
				(type default)
			)
			(layer "B.Fab")
		)
		(fp_line
			(start 0.12065 -0.2794)
			(end -0.12065 -0.2794)
			(stroke
				(width 0.1)
				(type default)
			)
			(layer "B.Fab")
		)
		(fp_line
			(start 0.12065 0.2794)
			(end 0.12065 0.3048)
			(stroke
				(width 0.1)
				(type default)
			)
			(layer "B.Fab")
		)
		(fp_line
			(start 0.12065 0.3048)
			(end 0.67945 0.3048)
			(stroke
				(width 0.1)
				(type default)
			)
			(layer "B.Fab")
		)
		(fp_line
			(start 0.67945 -0.305054)
			(end 0.12065 -0.305054)
			(stroke
				(width 0.1)
				(type default)
			)
			(layer "B.Fab")
		)
		(fp_line
			(start 0.67945 0.3048)
			(end 0.67945 -0.305054)
			(stroke
				(width 0.1)
				(type default)
			)
			(layer "B.Fab")
		)
		(pad "1" smd circle
			(at 0.40005 0 180)
			(size 0 0)
			(layers "B.Cu" "B.Mask" "B.Paste")
			(net "PVDDCR_SOC_P1")
		)
		(pad "2" smd circle
			(at -0.40005 0 180)
			(size 0 0)
			(layers "B.Cu" "B.Mask" "B.Paste")
			(net "GND")
		)
	)
	(footprint ""
		(layer "B.Cu")
		(at 239.141 -332.613)
		(property "Reference" "R849"
			(at 0 0 0)
			(layer "B.SilkS")
			(hide yes)
			(effects
				(font
					(size 1.27 1.27)
				)
				(justify mirror)
			)
		)
		(property "Value" ""
			(at 0 0 0)
			(layer "B.Fab")
			(effects
				(font
					(size 1.27 1.27)
				)
				(justify mirror)
			)
		)
		(duplicate_pad_numbers_are_jumpers no)
		(fp_line
			(start -0.32512 -0.175006)
			(end -0.32512 0.175006)
			(stroke
				(width 0.1)
				(type default)
			)
			(layer "B.Fab")
		)
		(fp_line
			(start -0.32512 0.175006)
			(end 0.32512 0.175006)
			(stroke
				(width 0.1)
				(type default)
			)
			(layer "B.Fab")
		)
		(fp_line
			(start 0.32512 -0.175006)
			(end -0.32512 -0.175006)
			(stroke
				(width 0.1)
				(type default)
			)
			(layer "B.Fab")
		)
		(fp_line
			(start 0.32512 0.175006)
			(end 0.32512 -0.175006)
			(stroke
				(width 0.1)
				(type default)
			)
			(layer "B.Fab")
		)
		(pad "1" smd rect
			(at 0.2667 0 180)
			(size 0.3048 0.381)
			(layers "B.Cu" "B.Mask" "B.Paste")
			(net "RST_SMB_RT_ROM_R1_N")
		)
		(pad "2" smd rect
			(at -0.2667 0)
			(size 0.3048 0.381)
			(layers "B.Cu" "B.Mask" "B.Paste")
			(net "GND")
		)
	)
	(footprint ""
		(layer "B.Cu")
		(at 372.937278 -143.504158)
		(property "Reference" "C465"
			(at 0 0 0)
			(layer "B.SilkS")
			(hide yes)
			(effects
				(font
					(size 1.27 1.27)
				)
				(justify mirror)
			)
		)
		(property "Value" ""
			(at 0 0 0)
			(layer "B.Fab")
			(effects
				(font
					(size 1.27 1.27)
				)
				(justify mirror)
			)
		)
		(duplicate_pad_numbers_are_jumpers no)
		(fp_line
			(start -0.7874 -0.4064)
			(end -0.7874 0.4064)
			(stroke
				(width 0.1524)
				(type default)
			)
			(layer "B.SilkS")
		)
		(fp_line
			(start -0.7874 0.4064)
			(end 0.7874 0.4064)
			(stroke
				(width 0.1524)
				(type default)
			)
			(layer "B.SilkS")
		)
		(fp_line
			(start 0.7874 -0.4064)
			(end -0.7874 -0.4064)
			(stroke
				(width 0.1524)
				(type default)
			)
			(layer "B.SilkS")
		)
		(fp_line
			(start 0.7874 0.4064)
			(end 0.7874 -0.4064)
			(stroke
				(width 0.1524)
				(type default)
			)
			(layer "B.SilkS")
		)
		(fp_line
			(start -0.67945 -0.3048)
			(end -0.67945 0.3048)
			(stroke
				(width 0.1)
				(type default)
			)
			(layer "B.Fab")
		)
		(fp_line
			(start -0.67945 0.3048)
			(end -0.120396 0.3048)
			(stroke
				(width 0.1)
				(type default)
			)
			(layer "B.Fab")
		)
		(fp_line
			(start -0.12065 -0.3048)
			(end -0.67945 -0.3048)
			(stroke
				(width 0.1)
				(type default)
			)
			(layer "B.Fab")
		)
		(fp_line
			(start -0.12065 -0.2794)
			(end -0.12065 -0.3048)
			(stroke
				(width 0.1)
				(type default)
			)
			(layer "B.Fab")
		)
		(fp_line
			(start -0.120396 0.2794)
			(end 0.12065 0.2794)
			(stroke
				(width 0.1)
				(type default)
			)
			(layer "B.Fab")
		)
		(fp_line
			(start -0.120396 0.3048)
			(end -0.120396 0.2794)
			(stroke
				(width 0.1)
				(type default)
			)
			(layer "B.Fab")
		)
		(fp_line
			(start 0.12065 -0.305054)
			(end 0.12065 -0.2794)
			(stroke
				(width 0.1)
				(type default)
			)
			(layer "B.Fab")
		)
		(fp_line
			(start 0.12065 -0.2794)
			(end -0.12065 -0.2794)
			(stroke
				(width 0.1)
				(type default)
			)
			(layer "B.Fab")
		)
		(fp_line
			(start 0.12065 0.2794)
			(end 0.12065 0.3048)
			(stroke
				(width 0.1)
				(type default)
			)
			(layer "B.Fab")
		)
		(fp_line
			(start 0.12065 0.3048)
			(end 0.67945 0.3048)
			(stroke
				(width 0.1)
				(type default)
			)
			(layer "B.Fab")
		)
		(fp_line
			(start 0.67945 -0.305054)
			(end 0.12065 -0.305054)
			(stroke
				(width 0.1)
				(type default)
			)
			(layer "B.Fab")
		)
		(fp_line
			(start 0.67945 0.3048)
			(end 0.67945 -0.305054)
			(stroke
				(width 0.1)
				(type default)
			)
			(layer "B.Fab")
		)
		(pad "1" smd circle
			(at 0.40005 0 180)
			(size 0 0)
			(layers "B.Cu" "B.Mask" "B.Paste")
			(net "PWRGD_PVDDCR_SOC_P0_R")
		)
		(pad "2" smd circle
			(at -0.40005 0 180)
			(size 0 0)
			(layers "B.Cu" "B.Mask" "B.Paste")
			(net "GND")
		)
	)
)
